# BASEBOARD_FAB2 (Tioga Pass) — schematic netlist excerpt (pin names and nets, part order shuffled) for the footprints in the layout excerpt that follows; sources: Cadence DE-HDL packaged netlist, KiCad conversion of Wiwynn_Tioga_Pass_MB.brd

R4G19  RES  33.2 1% CHIP  pkg 0402  page 221 : A = PWRGD_PVTT_ABC_CPU0_R ; B = PWRGD_PVTT_CPU0
FB9E1  BLM31SN500SN1L-GP  pkg DISCRET-GB1  page 240 : \1\ = P12V_STBY ; \2\ = VR_FET_SW_P12V_STBY_P3V3_STBY
SH3D2  SHUNT  EMPTY  pkg SH0201  page 214 : A = VSENSE_PVCCIO_CPU1_SKT_VSEN ; B = VSENSE_PVCCIO_CPU1_AVSP

(kicad_pcb
	(version 20260206)
	(generator "pcbnew")
	(generator_version "10.0")
	(general
		(thickness 1.6)
		(legacy_teardrops no)
	)
	(paper "A4")
	(title_block
		(title "Wiwynn_Tioga_Pass_MB.brd")
		(comment 1 "Tioga Pass / footprints 1003-1005 of 4770")
	)
	(layers
		(0 "F.Cu" signal "TOP")
		(4 "In1.Cu" signal "L2GND")
		(6 "In2.Cu" signal "L3")
		(8 "In3.Cu" signal "L4GND")
		(10 "In4.Cu" signal "L5")
		(12 "In5.Cu" signal "L6GND")
		(14 "In6.Cu" signal "L7VCC")
		(16 "In7.Cu" signal "L8VCC")
		(18 "In8.Cu" signal "L9GND")
		(20 "In9.Cu" signal "L10")
		(22 "In10.Cu" signal "L11GND")
		(24 "In11.Cu" signal "L12")
		(26 "In12.Cu" signal "L13GND")
		(2 "B.Cu" signal "BOTTOM")
		(9 "F.Adhes" user "F.Adhesive")
		(11 "B.Adhes" user "B.Adhesive")
		(13 "F.Paste" user "Package Geometry/Pastemask Top")
		(15 "B.Paste" user "Package Geometry/Pastemask Bottom")
		(5 "F.SilkS" user "Ref Des/Silkscreen Top")
		(7 "B.SilkS" user "Ref Des/Silkscreen Bottom")
		(1 "F.Mask" user "Board Geometry/Soldermask Top")
		(3 "B.Mask" user "Board Geometry/Soldermask Bottom")
		(17 "Dwgs.User" user "User.Drawings")
		(19 "Cmts.User" user "User.Comments")
		(21 "Eco1.User" user "User.Eco1")
		(23 "Eco2.User" user "User.Eco2")
		(25 "Edge.Cuts" user "Board Geometry/Outline")
		(27 "Margin" user)
		(31 "F.CrtYd" user "Package Geometry/Place Bound Top")
		(29 "B.CrtYd" user "Package Geometry/Place Bound Bottom")
		(35 "F.Fab" user "Ref Des/Assembly Top")
		(33 "B.Fab" user "Ref Des/Assembly Bottom")
	)
	(footprint ""
		(layer "F.Cu")
		(at 162.306 -64.8716 90)
		(property "Reference" "SH3D2"
			(at 0 0 90)
			(layer "F.SilkS")
			(hide yes)
			(effects
				(font
					(size 1.27 1.27)
				)
			)
		)
		(property "Value" ""
			(at 0 0 90)
			(layer "F.Fab")
			(effects
				(font
					(size 1.27 1.27)
				)
			)
		)
		(duplicate_pad_numbers_are_jumpers no)
		(fp_poly
			(pts
				(xy -0.1651 -0.0508) (xy -0.1651 0.5842) (xy 0.1651 0.5842) (xy 0.1651 -0.0508)
			)
			(stroke
				(width 0)
				(type default)
			)
			(fill no)
			(layer "F.CrtYd")
		)
		(fp_line
			(start 0.1651 -0.0508)
			(end 0.1651 0.5842)
			(stroke
				(width 0.1)
				(type default)
			)
			(layer "F.Fab")
		)
		(fp_line
			(start -0.1651 -0.0508)
			(end 0.1651 -0.0508)
			(stroke
				(width 0.1)
				(type default)
			)
			(layer "F.Fab")
		)
		(fp_line
			(start 0.1651 0.5842)
			(end -0.1651 0.5842)
			(stroke
				(width 0.1)
				(type default)
			)
			(layer "F.Fab")
		)
		(fp_line
			(start -0.1651 0.5842)
			(end -0.1651 -0.0508)
			(stroke
				(width 0.1)
				(type default)
			)
			(layer "F.Fab")
		)
		(pad "1" smd custom
			(at 0 0 270)
			(size 0.0762 0.0762)
			(layers "F.Cu" "F.Mask" "F.Paste")
			(net "VSENSE_PVCCIO_CPU1_SKT_VSEN")
			(options
				(clearance outline)
				(anchor circle)
			)
			(primitives
				(gr_poly
					(pts
						(arc
							(start -0.1524 -0.10795)
							(mid -0.098518 -0.130268)
							(end -0.0762 -0.18415)
						)
						(xy -0.0762 -0.22225) (xy 0.0762 -0.22225)
						(arc
							(start 0.0762 -0.18415)
							(mid 0.098518 -0.130268)
							(end 0.1524 -0.10795)
						)
						(xy 0.1524 0.22225) (xy -0.1524 0.22225)
					)
					(width 0)
					(fill yes)
				)
			)
		)
		(pad "2" smd custom
			(at 0 0.5334 90)
			(size 0.0762 0.0762)
			(layers "F.Cu" "F.Mask" "F.Paste")
			(net "VSENSE_PVCCIO_CPU1_AVSP")
			(options
				(clearance outline)
				(anchor circle)
			)
			(primitives
				(gr_poly
					(pts
						(arc
							(start -0.1524 -0.10795)
							(mid -0.098518 -0.130268)
							(end -0.0762 -0.18415)
						)
						(xy -0.0762 -0.22225) (xy 0.0762 -0.22225)
						(arc
							(start 0.0762 -0.18415)
							(mid 0.098518 -0.130268)
							(end 0.1524 -0.10795)
						)
						(xy 0.1524 0.22225) (xy -0.1524 0.22225)
					)
					(width 0)
					(fill yes)
				)
			)
		)
	)
	(footprint ""
		(layer "F.Cu")
		(at 481.369624 -24.552148 -90)
		(property "Reference" "FB9E1"
			(at 0 0 270)
			(layer "F.SilkS")
			(hide yes)
			(effects
				(font
					(size 1.27 1.27)
				)
			)
		)
		(property "Value" "*"
			(at -2.4511 -3.44805 270)
			(unlocked yes)
			(layer "F.Fab")
			(hide yes)
			(effects
				(font
					(size 0.889 0.889)
					(thickness 0.1524)
				)
			)
		)
		(property "Device Type" "BLM31SN500SN1L-GP_DISCRET-GB1-A"
			(at -2.4511 -4.97205 270)
			(unlocked yes)
			(layer "F.Fab")
			(hide yes)
			(effects
				(font
					(size 0.889 0.889)
					(thickness 0.1524)
				)
			)
		)
		(duplicate_pad_numbers_are_jumpers no)
		(fp_line
			(start -1.27 2.2352)
			(end -1.27 -2.2352)
			(stroke
				(width 0.1524)
				(type default)
			)
			(layer "F.SilkS")
		)
		(fp_line
			(start 1.27 2.2352)
			(end -1.27 2.2352)
			(stroke
				(width 0.1524)
				(type default)
			)
			(layer "F.SilkS")
		)
		(fp_line
			(start -1.27 -2.2352)
			(end 1.27 -2.2352)
			(stroke
				(width 0.1524)
				(type default)
			)
			(layer "F.SilkS")
		)
		(fp_line
			(start 1.27 -2.2352)
			(end 1.27 2.2352)
			(stroke
				(width 0.1524)
				(type default)
			)
			(layer "F.SilkS")
		)
		(fp_rect
			(start -0.8001 1.6002)
			(end 0.8001 -1.6002)
			(stroke
				(width 0)
				(type default)
			)
			(fill no)
			(layer "F.CrtYd")
		)
		(fp_poly
			(pts
				(xy -0.8001 -1.6002) (xy 1.524 -1.6002) (xy 1.524 -2.3114) (xy -1.524 -2.3114) (xy -1.524 2.3114)
				(xy 1.524 2.3114) (xy 1.524 -1.5875) (xy 0.8001 -1.5875) (xy 0.8001 1.6002) (xy -0.8001 1.6002)
			)
			(stroke
				(width 0)
				(type default)
			)
			(fill no)
			(layer "F.CrtYd")
		)
		(fp_rect
			(start -1.524 2.3114)
			(end 1.524 -2.3114)
			(stroke
				(width 0)
				(type default)
			)
			(fill no)
			(layer "F.Fab")
		)
		(pad "1" smd rect
			(at 0 -1.5367 270)
			(size 2.032 1.397)
			(drill
				(offset 0 0.2032)
			)
			(layers "F.Cu" "F.Mask" "F.Paste")
			(net "P12V_STBY")
		)
		(pad "2" smd rect
			(at 0 1.5367 270)
			(size 2.032 1.397)
			(drill
				(offset 0 -0.2032)
			)
			(layers "F.Cu" "F.Mask" "F.Paste")
			(net "VR_FET_SW_P12V_STBY_P3V3_STBY")
		)
	)
	(footprint ""
		(layer "F.Cu")
		(at 180.0606 -4.445 180)
		(property "Reference" "R4G19"
			(at 0 0 180)
			(layer "F.SilkS")
			(hide yes)
			(effects
				(font
					(size 1.27 1.27)
				)
			)
		)
		(property "Value" ""
			(at 0 0 180)
			(layer "F.Fab")
			(effects
				(font
					(size 1.27 1.27)
				)
			)
		)
		(duplicate_pad_numbers_are_jumpers no)
		(fp_poly
			(pts
				(xy -0.2794 -0.1016) (xy 0.2794 -0.1016) (xy 0.2794 0.9906) (xy -0.2794 0.9906)
			)
			(stroke
				(width 0)
				(type default)
			)
			(fill no)
			(layer "F.CrtYd")
		)
		(fp_line
			(start 0.2794 0.9906)
			(end 0.2794 -0.1016)
			(stroke
				(width 0.1)
				(type default)
			)
			(layer "F.Fab")
		)
		(fp_line
			(start 0.2794 -0.1016)
			(end -0.2794 -0.1016)
			(stroke
				(width 0.1)
				(type default)
			)
			(layer "F.Fab")
		)
		(fp_line
			(start -0.2794 0.9906)
			(end 0.2794 0.9906)
			(stroke
				(width 0.1)
				(type default)
			)
			(layer "F.Fab")
		)
		(fp_line
			(start -0.2794 -0.1016)
			(end -0.2794 0.9906)
			(stroke
				(width 0.1)
				(type default)
			)
			(layer "F.Fab")
		)
		(pad "1" smd rect
			(at 0 0 180)
			(size 0.508 0.508)
			(layers "F.Cu" "F.Mask" "F.Paste")
			(net "PWRGD_PVTT_ABC_CPU0_R")
		)
		(pad "2" smd rect
			(at 0 0.889 180)
			(size 0.508 0.508)
			(layers "F.Cu" "F.Mask" "F.Paste")
			(net "PWRGD_PVTT_CPU0")
		)
		(zone
			(layer "F.Cu")
			(hatch none 0.5)
			(connect_pads
				(clearance 0)
			)
			(min_thickness 0.25)
			(keepout
				(tracks not_allowed)
				(vias allowed)
				(pads allowed)
				(copperpour not_allowed)
				(footprints allowed)
			)
			(placement
				(enabled no)
				(sheetname "")
			)
			(fill
				(thermal_gap 0.5)
				(thermal_bridge_width 0.5)
				(island_removal_mode 0)
			)
			(polygon
				(pts
					(xy 180.3146 -5.08) (xy 179.8066 -5.08) (xy 179.8066 -4.699) (xy 180.3146 -4.699)
				)
			)
		)
		(zone
			(layer "F.Cu")
			(hatch none 0.5)
			(connect_pads
				(clearance 0)
			)
			(min_thickness 0.25)
			(keepout
				(tracks allowed)
				(vias not_allowed)
				(pads allowed)
				(copperpour not_allowed)
				(footprints allowed)
			)
			(placement
				(enabled no)
				(sheetname "")
			)
			(fill
				(thermal_gap 0.5)
				(thermal_bridge_width 0.5)
				(island_removal_mode 0)
			)
			(polygon
				(pts
					(xy 180.3146 -4.699) (xy 179.8066 -4.699) (xy 179.8066 -5.08) (xy 180.3146 -5.08)
				)
			)
		)
	)
)
